FILE_TYPE = CONNECTIVITY;
{Allegro Design Entry HDL 17.2-2016 S081 (4005846) 1/11/2022}
"PAGE_NUMBER" = 30;
0"NC";
1"P1V5_BAT\g";
2"PVDDCR_CPU0_P0\g";
3"PVDDCR_CPU0_P0\g";
4"PVDDCR_CPU1_P0\g";
5"PVDDCR_CPU1_P0\g";
6"PVDDCR_SOC_P0\g";
7"PVDD_33_S5\g";
8"PVDD18_S5_P0\g";
9"PVDD11_S3_P0\g";
10"PVDDCR_SOC_P0\g";
11"PVDDIO_P0\g";
%"GENOA_SP5"
"27","(-2475,3550)","0","pure_quanta","I28";
;
LOCATION"U25"
$SEC"27"
CDS_SEC"27"
PART_TYPE"SMLF"
MATERIAL"IO"
VALUE"SOCKET6096_13568-001"
PART_NUMBER"DGA^6000030"
CDS_LIB"pure_quanta"
CDS_LMAN_SYM_OUTLINE"-500,3075,500,-3075"
NEEDS_NO_SIZE"TRUE";
"VDD_11_S3_CT19"
$PN"CT19"9;
"VDD_11_S3_CT22"
$PN"CT22"9;
"VDD_11_S3_CW4"
$PN"CW4"9;
"VDD_11_S3_CW11"
$PN"CW11"9;
"VDD_11_S3_CW18"
$PN"CW18"9;
"VDD_11_S3_CY22"
$PN"CY22"9;
"VDD_11_S3_DB5"
$PN"DB5"9;
"VDD_11_S3_DB12"
$PN"DB12"9;
"VDD_11_S3_DB19"
$PN"DB19"9;
"VDD_11_S3_DE4"
$PN"DE4"9;
"VDD_11_S3_DE11"
$PN"DE11"9;
"VDD_11_S3_DE18"
$PN"DE18"9;
"VDD_11_S3_DG5"
$PN"DG5"9;
"VDDIO_CT64"
$PN"CT64"11;
"VDDIO_CT71"
$PN"CT71"11;
"VDDIO_CW58"
$PN"CW58"11;
"VDDIO_CW65"
$PN"CW65"11;
"VDDIO_CW72"
$PN"CW72"11;
"VDDIO_CY54"
$PN"CY54"11;
"VDDIO_DB57"
$PN"DB57"11;
"VDDIO_DB64"
$PN"DB64"11;
"VDDIO_DB71"
$PN"DB71"11;
"VDDIO_DE58"
$PN"DE58"11;
"VDDIO_DE65"
$PN"DE65"11;
"VDDIO_DE72"
$PN"DE72"11;
"VDDIO_DG64"
$PN"DG64"11;
"VDDIO_DG71"
$PN"DG71"11;
"VDDBT_RTC_G"
$PN"BN23"1;
"VDDIO_AUDIO"
$PN"BH27"8;
"VDD_33_S5_BP51"
$PN"BP51"7;
"VDD_33_S5_BN52"
$PN"BN52"7;
"VDD_11_S3_CT12"
$PN"CT12"9;
"VDD_18_S5_BB53"
$PN"BB53"8;
"VDD_18_S5_BB51"
$PN"BB51"8;
"VDD_18_S5_BA54"
$PN"BA54"8;
"VDD_18_S5_BA52"
$PN"BA52"8;
"VDD_18_S5_BA50"
$PN"BA50"8;
"VDD_18_S5_AY53"
$PN"AY53"8;
"VDD_18_S5_AY51"
$PN"AY51"8;
"VDD_18_S5_AW54"
$PN"AW54"8;
"VDD_18_S5_AW52"
$PN"AW52"8;
"VDD_18_S5_BC54"
$PN"BC54"8;
"VDD_18_S5_BC52"
$PN"BC52"8;
"VDD_18_S5_AW50"
$PN"AW50"8;
"VDD_18_S5_AV53"
$PN"AV53"8;
"VDD_18_S5_AV51"
$PN"AV51"8;
"VDD_18_S5_AV49"
$PN"AV49"8;
"VDD_18_S5_AU52"
$PN"AU52"8;
"VDD_18_S5_AU50"
$PN"AU50"8;
"VDD_18_S5_AT53"
$PN"AT53"8;
"VDD_18_S5_AT51"
$PN"AT51"8;
"VDD_18_S5_AR54"
$PN"AR54"8;
"VDD_18_S5_AR52"
$PN"AR52"8;
"VDD_18_S5_AU54"
$PN"AU54"8;
"VDD_11_S3_CT5"
$PN"CT5"9;
"VDD_11_S3_CN18"
$PN"CN18"9;
"VDD_11_S3_CN11"
$PN"CN11"9;
"VDD_11_S3_CN4"
$PN"CN4"9;
"VDD_11_S3_CM22"
$PN"CM22"9;
"VDD_11_S3_CK19"
$PN"CK19"9;
"VDD_11_S3_CK12"
$PN"CK12"9;
"VDD_11_S3_CK5"
$PN"CK5"9;
"VDD_11_S3_CJ22"
$PN"CJ22"9;
"VDD_11_S3_CG18"
$PN"CG18"9;
"VDD_11_S3_CG11"
$PN"CG11"9;
"VDD_11_S3_CG4"
$PN"CG4"9;
"VDD_11_S3_CF22"
$PN"CF22"9;
"VDD_11_S3_CD19"
$PN"CD19"9;
"VDD_11_S3_CD12"
$PN"CD12"9;
"VDD_11_S3_CD5"
$PN"CD5"9;
"VDD_11_S3_CB22"
$PN"CB22"9;
"VDD_11_S3_CA18"
$PN"CA18"9;
"VDD_11_S3_CA11"
$PN"CA11"9;
"VDD_11_S3_CA4"
$PN"CA4"9;
"VDD_11_S3_BV22"
$PN"BV22"9;
"VDD_11_S3_BV19"
$PN"BV19"9;
"VDD_11_S3_BV12"
$PN"BV12"9;
"VDD_11_S3_BV5"
$PN"BV5"9;
"VDD_11_S3_BR18"
$PN"BR18"9;
"VDD_11_S3_BR11"
$PN"BR11"9;
"VDD_11_S3_BR4"
$PN"BR4"9;
"VDD_11_S3_BP22"
$PN"BP22"9;
"VDD_11_S3_BN48"
$PN"BN48"9;
"VDD_11_S3_BN44"
$PN"BN44"9;
"VDD_11_S3_BN40"
$PN"BN40"9;
"VDD_11_S3_BN33"
$PN"BN33"9;
"VDD_11_S3_BN29"
$PN"BN29"9;
"VDD_11_S3_BN25"
$PN"BN25"9;
"VDD_11_S3_BM49"
$PN"BM49"9;
"VDD_11_S3_BM47"
$PN"BM47"9;
"VDD_11_S3_BM45"
$PN"BM45"9;
"VDD_11_S3_BM43"
$PN"BM43"9;
"VDD_11_S3_BM41"
$PN"BM41"9;
"VDD_11_S3_BM39"
$PN"BM39"9;
"VDD_11_S3_BM36"
$PN"BM36"9;
"VDD_11_S3_BM34"
$PN"BM34"9;
"VDD_11_S3_BM32"
$PN"BM32"9;
"VDD_11_S3_BM30"
$PN"BM30"9;
"VDD_11_S3_BM28"
$PN"BM28"9;
"VDD_11_S3_BM26"
$PN"BM26"9;
"VDD_11_S3_BM24"
$PN"BM24"9;
"VDD_11_S3_BM22"
$PN"BM22"9;
"VDD_11_S3_BM19"
$PN"BM19"9;
"VDD_11_S3_BM12"
$PN"BM12"9;
"VDD_11_S3_BL48"
$PN"BL48"9;
"VDD_11_S3_BL27"
$PN"BL27"9;
"VDD_11_S3_BL25"
$PN"BL25"9;
"VDD_11_S3_BL23"
$PN"BL23"9;
"VDD_11_S3_BK49"
$PN"BK49"9;
"VDD_11_S3_BK28"
$PN"BK28"9;
"VDD_11_S3_BK26"
$PN"BK26"9;
"VDD_11_S3_BK24"
$PN"BK24"9;
"VDD_11_S3_BK22"
$PN"BK22"9;
"VDD_11_S3_BJ27"
$PN"BJ27"9;
"VDD_11_S3_BJ25"
$PN"BJ25"9;
"VDD_11_S3_BJ23"
$PN"BJ23"9;
"VDD_11_S3_BJ18"
$PN"BJ18"9;
"VDDIO_CT57"
$PN"CT57"11;
"VDDIO_CT54"
$PN"CT54"11;
"VDDIO_CN72"
$PN"CN72"11;
"VDDIO_CN65"
$PN"CN65"11;
"VDDIO_CN58"
$PN"CN58"11;
"VDDIO_CM54"
$PN"CM54"11;
"VDDIO_CK71"
$PN"CK71"11;
"VDDIO_CK64"
$PN"CK64"11;
"VDDIO_CK57"
$PN"CK57"11;
"VDDIO_CJ54"
$PN"CJ54"11;
"VDDIO_CG72"
$PN"CG72"11;
"VDDIO_CG65"
$PN"CG65"11;
"VDDIO_CG58"
$PN"CG58"11;
"VDDIO_CF54"
$PN"CF54"11;
"VDDIO_CD71"
$PN"CD71"11;
"VDDIO_CD64"
$PN"CD64"11;
"VDDIO_CD57"
$PN"CD57"11;
"VDDIO_CB54"
$PN"CB54"11;
"VDDIO_CA72"
$PN"CA72"11;
"VDDIO_CA65"
$PN"CA65"11;
"VDDIO_CA58"
$PN"CA58"11;
"VDDIO_BV71"
$PN"BV71"11;
"VDDIO_BV64"
$PN"BV64"11;
"VDDIO_BV57"
$PN"BV57"11;
"VDDIO_BV54"
$PN"BV54"11;
"VDDIO_BR72"
$PN"BR72"11;
"VDDIO_BR65"
$PN"BR65"11;
"VDDIO_BR58"
$PN"BR58"11;
"VDDIO_BN54"
$PN"BN54"11;
"VDDIO_BM71"
$PN"BM71"11;
"VDDIO_BM64"
$PN"BM64"11;
"VDDIO_BM57"
$PN"BM57"11;
"VDDIO_BM53"
$PN"BM53"11;
"VDDIO_BM51"
$PN"BM51"11;
"VDDIO_BL54"
$PN"BL54"11;
"VDDIO_BL52"
$PN"BL52"11;
"VDDIO_BL50"
$PN"BL50"11;
"VDDIO_BK53"
$PN"BK53"11;
"VDDIO_BK51"
$PN"BK51"11;
"VDDIO_BJ72"
$PN"BJ72"11;
"VDDIO_BJ65"
$PN"BJ65"11;
"VDDIO_BJ58"
$PN"BJ58"11;
"VDDIO_BJ54"
$PN"BJ54"11;
"VDDIO_BJ52"
$PN"BJ52"11;
"VDDIO_BJ50"
$PN"BJ50"11;
"VDDIO_BH53"
$PN"BH53"11;
"VDDIO_BH51"
$PN"BH51"11;
"VDDIO_BG54"
$PN"BG54"11;
"VDDIO_BG52"
$PN"BG52"11;
"VDDIO_BG50"
$PN"BG50"11;
"VDDIO_BF71"
$PN"BF71"11;
"VDDIO_BF64"
$PN"BF64"11;
"VDDIO_BF57"
$PN"BF57"11;
"VDDIO_BF53"
$PN"BF53"11;
"VDDIO_BF51"
$PN"BF51"11;
"VDDIO_BD54"
$PN"BD54"11;
"VDDIO_BD52"
$PN"BD52"11;
"VDDIO_BD50"
$PN"BD50"11;
"VDDIO_BA72"
$PN"BA72"11;
"VDDIO_BA65"
$PN"BA65"11;
"VDDIO_BA58"
$PN"BA58"11;
"VDDIO_AV71"
$PN"AV71"11;
"VDDIO_AV64"
$PN"AV64"11;
"VDDIO_AV57"
$PN"AV57"11;
"VDDIO_AR72"
$PN"AR72"11;
"VDDIO_AR65"
$PN"AR65"11;
"VDDIO_AR58"
$PN"AR58"11;
"VDDIO_AM71"
$PN"AM71"11;
"VDDIO_AM64"
$PN"AM64"11;
"VDDIO_AM57"
$PN"AM57"11;
"VDDIO_AM54"
$PN"AM54"11;
"VDDIO_AJ72"
$PN"AJ72"11;
"VDDIO_AJ65"
$PN"AJ65"11;
"VDDIO_AJ58"
$PN"AJ58"11;
"VDDIO_AH54"
$PN"AH54"11;
"VDDIO_AF71"
$PN"AF71"11;
"VDDIO_AF64"
$PN"AF64"11;
"VDDIO_AF57"
$PN"AF57"11;
"VDDIO_AD54"
$PN"AD54"11;
"VDDIO_AC72"
$PN"AC72"11;
"VDDIO_AC65"
$PN"AC65"11;
"VDDIO_AC58"
$PN"AC58"11;
"VDDIO_AA54"
$PN"AA54"11;
"VDDIO_Y71"
$PN"Y71"11;
"VDDIO_Y64"
$PN"Y64"11;
"VDDIO_Y57"
$PN"Y57"11;
"VDDIO_V54"
$PN"V54"11;
"VDDIO_U72"
$PN"U72"11;
"VDDIO_U65"
$PN"U65"11;
"VDDIO_U58"
$PN"U58"11;
"VDDIO_P71"
$PN"P71"11;
"VDDIO_P64"
$PN"P64"11;
"VDDIO_P57"
$PN"P57"11;
"VDDIO_P54"
$PN"P54"11;
"VDDIO_L72"
$PN"L72"11;
"VDDIO_L65"
$PN"L65"11;
"VDDIO_L58"
$PN"L58"11;
"VDDIO_K54"
$PN"K54"11;
"VDDIO_H71"
$PN"H71"11;
"VDDIO_H64"
$PN"H64"11;
"VDDIO_H57"
$PN"H57"11;
%"GENOA_SP5"
"23","(-725,4350)","0","pure_quanta","I29";
;
LOCATION"U25"
$SEC"23"
CDS_SEC"23"
PART_TYPE"SMLF"
MATERIAL"IO"
VALUE"SOCKET6096_13568-001"
PART_NUMBER"DGA^6000030"
CDS_LMAN_SYM_OUTLINE"-550,2000,550,-2000"
CDS_LIB"pure_quanta"
NEEDS_NO_SIZE"TRUE";
"TEST6_X3D6"
$PN"B36"0;
"TEST4_CCD15"
$PN"C23"0;
"TEST4_CCD12"
$PN"C58"0;
"TEST5_CCD12"
$PN"C59"0;
"TEST5_CCD15"
$PN"D23"0;
"TEST4_CCD14"
$PN"DF41"0;
"TEST5_CCD14"
$PN"DG42"0;
"TEST4_CCD13"
$PN"DH13"0;
"TEST5_CCD13"
$PN"DH14"0;
"TEST6_X3D7"
$PN"DJ57"0;
"RSVD_A60"
$PN"A60"0;
"RSVD_BD7"
$PN"BD7"0;
"RSVD_D36"
$PN"D36"0;
"RSVD_BD58"
$PN"BD58"0;
"RSVD_BD55"
$PN"BD55"0;
"RSVD_A54"
$PN"A54"0;
"RSVD_A51"
$PN"A51"0;
"RSVD_A50"
$PN"A50"0;
"RSVD_A48"
$PN"A48"0;
"RSVD_C53"
$PN"C53"0;
"RSVD_A45"
$PN"A45"0;
"RSVD_C35"
$PN"C35"0;
"RSVD_D65"
$PN"D65"0;
"RSVD_A42"
$PN"A42"0;
"RSVD_C34"
$PN"C34"0;
"RSVD_D62"
$PN"D62"0;
"RSVD_BD21"
$PN"BD21"0;
"RSVD_A41"
$PN"A41"0;
"RSVD_C31"
$PN"C31"0;
"RSVD_D58"
$PN"D58"0;
"RSVD_BD18"
$PN"BD18"0;
"RSVD_DJ4"
$PN"DJ4"0;
"RSVD_A35"
$PN"A35"0;
"RSVD_B40"
$PN"B40"0;
"RSVD_BD14"
$PN"BD14"0;
"RSVD_DH21"
$PN"DH21"0;
"RSVD_A31"
$PN"A31"0;
"RSVD_D34"
$PN"D34"0;
"RSVD_BD11"
$PN"BD11"0;
"RSVD_DH17"
$PN"DH17"0;
"RSVD_A59"
$PN"A59"0;
"RSVD_D22"
$PN"D22"0;
"RSVD_DG17"
$PN"DG17"0;
"RSVD_A57"
$PN"A57"0;
"RSVD_D11"
$PN"D11"0;
"RSVD_BD4"
$PN"BD4"0;
"RSVD_BD72"
$PN"BD72"0;
"RSVD_A56"
$PN"A56"0;
"RSVD_D8"
$PN"D8"0;
"RSVD_E36"
$PN"E36"0;
"RSVD_BD69"
$PN"BD69"0;
"RSVD_A55"
$PN"A55"0;
"RSVD_D4"
$PN"D4"0;
"RSVD_E33"
$PN"E33"0;
"RSVD_BD65"
$PN"BD65"0;
"RSVD_C54"
$PN"C54"0;
"RSVD_D72"
$PN"D72"0;
"RSVD_BD62"
$PN"BD62"0;
%"VCC_CORE"
"1","(-1675,6625)","0","pure_quanta_power","I40";
;
HDL_POWER"PVDDIO_P0"
CDS_LIB"pure_quanta_power";
"A"11;
%"UNIVERSAL_POWER"
"1","(-1475,825)","0","pure_quanta_power","I41";
;
HDL_POWER"P1V5_BAT"
CDS_LIB"pure_quanta_power";
"A"1;
%"GENOA_SP5"
"24","(-8050,3325)","0","pure_quanta","I42";
;
LOCATION"U25"
$SEC"24"
CDS_SEC"24"
PART_TYPE"SMLF"
MATERIAL"IO"
VALUE"SOCKET6096_13568-001"
PART_NUMBER"DGA^6000030"
CDS_LIB"pure_quanta"
CDS_LMAN_SYM_OUTLINE"-500,3150,500,-3150"
NEEDS_NO_SIZE"TRUE";
"VDDCR_CPU0_AU33"
$PN"AU33"3;
"VDDCR_CPU0_AU25"
$PN"AU25"3;
"VDDCR_CPU0_AU48"
$PN"AU48"3;
"VDDCR_CPU0_AU44"
$PN"AU44"3;
"VDDCR_CPU0_AU29"
$PN"AU29"3;
"VDDCR_CPU0_AT49"
$PN"AT49"3;
"VDDCR_CPU0_AU46"
$PN"AU46"3;
"VDDCR_CPU0_AU42"
$PN"AU42"3;
"VDDCR_CPU0_Y35"
$PN"Y35"3;
"VDDCR_CPU0_Y36"
$PN"Y36"3;
"VDDCR_CPU0_Y40"
$PN"Y40"3;
"VDDCR_CPU0_Y41"
$PN"Y41"3;
"VDDCR_CPU0_AB23"
$PN"AB23"3;
"VDDCR_CPU0_AB24"
$PN"AB24"3;
"VDDCR_CPU0_AB26"
$PN"AB26"3;
"VDDCR_CPU0_AB27"
$PN"AB27"3;
"VDDCR_CPU0_AB29"
$PN"AB29"3;
"VDDCR_CPU0_AB30"
$PN"AB30"3;
"VDDCR_CPU0_AB32"
$PN"AB32"3;
"VDDCR_CPU0_AB33"
$PN"AB33"3;
"VDDCR_CPU0_AB43"
$PN"AB43"3;
"VDDCR_CPU0_AB44"
$PN"AB44"3;
"VDDCR_CPU0_AB46"
$PN"AB46"3;
"VDDCR_CPU0_AB47"
$PN"AB47"3;
"VDDCR_CPU0_AB49"
$PN"AB49"3;
"VDDCR_CPU0_AB50"
$PN"AB50"3;
"VDDCR_CPU0_AB52"
$PN"AB52"3;
"VDDCR_CPU0_AB53"
$PN"AB53"3;
"VDDCR_CPU0_AC35"
$PN"AC35"3;
"VDDCR_CPU0_AC36"
$PN"AC36"3;
"VDDCR_CPU0_AC40"
$PN"AC40"3;
"VDDCR_CPU0_AC41"
$PN"AC41"3;
"VDDCR_CPU0_AF23"
$PN"AF23"3;
"VDDCR_CPU0_AF24"
$PN"AF24"3;
"VDDCR_CPU0_AF26"
$PN"AF26"3;
"VDDCR_CPU0_AF27"
$PN"AF27"3;
"VDDCR_CPU0_AF29"
$PN"AF29"3;
"VDDCR_CPU0_AF30"
$PN"AF30"3;
"VDDCR_CPU0_AF32"
$PN"AF32"3;
"VDDCR_CPU0_AF33"
$PN"AF33"3;
"VDDCR_CPU0_AF43"
$PN"AF43"3;
"VDDCR_CPU0_AF44"
$PN"AF44"3;
"VDDCR_CPU0_AF46"
$PN"AF46"3;
"VDDCR_CPU0_AF47"
$PN"AF47"3;
"VDDCR_CPU0_AF49"
$PN"AF49"3;
"VDDCR_CPU0_AF50"
$PN"AF50"3;
"VDDCR_CPU0_AF52"
$PN"AF52"3;
"VDDCR_CPU0_AF53"
$PN"AF53"3;
"VDDCR_CPU0_AG35"
$PN"AG35"3;
"VDDCR_CPU0_AG36"
$PN"AG36"3;
"VDDCR_CPU0_AG40"
$PN"AG40"3;
"VDDCR_CPU0_AG41"
$PN"AG41"3;
"VDDCR_CPU0_AK23"
$PN"AK23"3;
"VDDCR_CPU0_AK24"
$PN"AK24"3;
"VDDCR_CPU0_AK26"
$PN"AK26"3;
"VDDCR_CPU0_AK27"
$PN"AK27"3;
"VDDCR_CPU0_AK29"
$PN"AK29"3;
"VDDCR_CPU0_AK30"
$PN"AK30"3;
"VDDCR_CPU0_AK32"
$PN"AK32"3;
"VDDCR_CPU0_AK33"
$PN"AK33"3;
"VDDCR_CPU0_AK43"
$PN"AK43"3;
"VDDCR_CPU0_AK44"
$PN"AK44"3;
"VDDCR_CPU0_AK46"
$PN"AK46"3;
"VDDCR_CPU0_AK47"
$PN"AK47"3;
"VDDCR_CPU0_AK49"
$PN"AK49"3;
"VDDCR_CPU0_AK50"
$PN"AK50"3;
"VDDCR_CPU0_AK52"
$PN"AK52"3;
"VDDCR_CPU0_AK53"
$PN"AK53"3;
"VDDCR_CPU0_AL35"
$PN"AL35"3;
"VDDCR_CPU0_AL36"
$PN"AL36"3;
"VDDCR_CPU0_AL40"
$PN"AL40"3;
"VDDCR_CPU0_AL41"
$PN"AL41"3;
"VDDCR_CPU0_AP23"
$PN"AP23"3;
"VDDCR_CPU0_AP24"
$PN"AP24"3;
"VDDCR_CPU0_AP26"
$PN"AP26"3;
"VDDCR_CPU0_AP27"
$PN"AP27"3;
"VDDCR_CPU0_AP29"
$PN"AP29"3;
"VDDCR_CPU0_AP30"
$PN"AP30"3;
"VDDCR_CPU0_AP32"
$PN"AP32"3;
"VDDCR_CPU0_AP33"
$PN"AP33"3;
"VDDCR_CPU0_AP43"
$PN"AP43"3;
"VDDCR_CPU0_AP44"
$PN"AP44"3;
"VDDCR_CPU0_AP46"
$PN"AP46"3;
"VDDCR_CPU0_AP47"
$PN"AP47"3;
"VDDCR_CPU0_AP49"
$PN"AP49"3;
"VDDCR_CPU0_AP50"
$PN"AP50"3;
"VDDCR_CPU0_AP52"
$PN"AP52"3;
"VDDCR_CPU0_AP53"
$PN"AP53"3;
"VDDCR_CPU0_AR23"
$PN"AR23"3;
"VDDCR_CPU0_AR25"
$PN"AR25"3;
"VDDCR_CPU0_AR27"
$PN"AR27"3;
"VDDCR_CPU0_AR29"
$PN"AR29"3;
"VDDCR_CPU0_AR31"
$PN"AR31"3;
"VDDCR_CPU0_AR33"
$PN"AR33"3;
"VDDCR_CPU0_AR35"
$PN"AR35"3;
"VDDCR_CPU0_AR40"
$PN"AR40"3;
"VDDCR_CPU0_AR42"
$PN"AR42"3;
"VDDCR_CPU0_AR44"
$PN"AR44"3;
"VDDCR_CPU0_AR46"
$PN"AR46"3;
"VDDCR_CPU0_AR48"
$PN"AR48"3;
"VDDCR_CPU0_AR50"
$PN"AR50"3;
"VDDCR_CPU0_AT24"
$PN"AT24"3;
"VDDCR_CPU0_AT26"
$PN"AT26"3;
"VDDCR_CPU0_AT28"
$PN"AT28"3;
"VDDCR_CPU0_AT30"
$PN"AT30"3;
"VDDCR_CPU0_AT32"
$PN"AT32"3;
"VDDCR_CPU0_AT34"
$PN"AT34"3;
"VDDCR_CPU0_AT36"
$PN"AT36"3;
"VDDCR_CPU0_AT39"
$PN"AT39"3;
"VDDCR_CPU0_AT41"
$PN"AT41"3;
"VDDCR_CPU0_AT43"
$PN"AT43"3;
"VDDCR_CPU0_AT45"
$PN"AT45"3;
"VDDCR_CPU0_AT47"
$PN"AT47"3;
"VDDCR_CPU0_B19"
$PN"B19"2;
"VDDCR_CPU0_B20"
$PN"B20"2;
"VDDCR_CPU0_B22"
$PN"B22"2;
"VDDCR_CPU0_B23"
$PN"B23"2;
"VDDCR_CPU0_B25"
$PN"B25"2;
"VDDCR_CPU0_B26"
$PN"B26"2;
"VDDCR_CPU0_B28"
$PN"B28"2;
"VDDCR_CPU0_B29"
$PN"B29"2;
"VDDCR_CPU0_B31"
$PN"B31"2;
"VDDCR_CPU0_B32"
$PN"B32"2;
"VDDCR_CPU0_B34"
$PN"B34"2;
"VDDCR_CPU0_B35"
$PN"B35"2;
"VDDCR_CPU0_B41"
$PN"B41"2;
"VDDCR_CPU0_B42"
$PN"B42"2;
"VDDCR_CPU0_B44"
$PN"B44"2;
"VDDCR_CPU0_B45"
$PN"B45"2;
"VDDCR_CPU0_B47"
$PN"B47"2;
"VDDCR_CPU0_B48"
$PN"B48"2;
"VDDCR_CPU0_B50"
$PN"B50"2;
"VDDCR_CPU0_B51"
$PN"B51"2;
"VDDCR_CPU0_B53"
$PN"B53"2;
"VDDCR_CPU0_B54"
$PN"B54"2;
"VDDCR_CPU0_B56"
$PN"B56"2;
"VDDCR_CPU0_B57"
$PN"B57"2;
"VDDCR_CPU0_C20"
$PN"C20"2;
"VDDCR_CPU0_D55"
$PN"D55"2;
"VDDCR_CPU0_D56"
$PN"D56"2;
"VDDCR_CPU0_E22"
$PN"E22"2;
"VDDCR_CPU0_E25"
$PN"E25"2;
"VDDCR_CPU0_E28"
$PN"E28"2;
"VDDCR_CPU0_E31"
$PN"E31"2;
"VDDCR_CPU0_E34"
$PN"E34"2;
"VDDCR_CPU0_E35"
$PN"E35"2;
"VDDCR_CPU0_E42"
$PN"E42"2;
"VDDCR_CPU0_E45"
$PN"E45"2;
"VDDCR_CPU0_E48"
$PN"E48"2;
"VDDCR_CPU0_E51"
$PN"E51"2;
"VDDCR_CPU0_E54"
$PN"E54"2;
"VDDCR_CPU0_F22"
$PN"F22"2;
"VDDCR_CPU0_F25"
$PN"F25"2;
"VDDCR_CPU0_F28"
$PN"F28"2;
"VDDCR_CPU0_F31"
$PN"F31"2;
"VDDCR_CPU0_F34"
$PN"F34"2;
"VDDCR_CPU0_F42"
$PN"F42"2;
"VDDCR_CPU0_F45"
$PN"F45"2;
"VDDCR_CPU0_F48"
$PN"F48"2;
"VDDCR_CPU0_F51"
$PN"F51"2;
"VDDCR_CPU0_F54"
$PN"F54"2;
"VDDCR_CPU0_G35"
$PN"G35"2;
"VDDCR_CPU0_G36"
$PN"G36"2;
"VDDCR_CPU0_G40"
$PN"G40"2;
"VDDCR_CPU0_G41"
$PN"G41"2;
"VDDCR_CPU0_H23"
$PN"H23"2;
"VDDCR_CPU0_H24"
$PN"H24"2;
"VDDCR_CPU0_H26"
$PN"H26"2;
"VDDCR_CPU0_H27"
$PN"H27"2;
"VDDCR_CPU0_H29"
$PN"H29"2;
"VDDCR_CPU0_H30"
$PN"H30"2;
"VDDCR_CPU0_H32"
$PN"H32"2;
"VDDCR_CPU0_H33"
$PN"H33"2;
"VDDCR_CPU0_H43"
$PN"H43"2;
"VDDCR_CPU0_H44"
$PN"H44"2;
"VDDCR_CPU0_H46"
$PN"H46"2;
"VDDCR_CPU0_H47"
$PN"H47"2;
"VDDCR_CPU0_H49"
$PN"H49"2;
"VDDCR_CPU0_H50"
$PN"H50"2;
"VDDCR_CPU0_H52"
$PN"H52"2;
"VDDCR_CPU0_H53"
$PN"H53"2;
"VDDCR_CPU0_J35"
$PN"J35"2;
"VDDCR_CPU0_J36"
$PN"J36"2;
"VDDCR_CPU0_J40"
$PN"J40"2;
"VDDCR_CPU0_J41"
$PN"J41"2;
"VDDCR_CPU0_M23"
$PN"M23"2;
"VDDCR_CPU0_M24"
$PN"M24"2;
"VDDCR_CPU0_M26"
$PN"M26"2;
"VDDCR_CPU0_M27"
$PN"M27"2;
"VDDCR_CPU0_M29"
$PN"M29"2;
"VDDCR_CPU0_M30"
$PN"M30"2;
"VDDCR_CPU0_M32"
$PN"M32"2;
"VDDCR_CPU0_M33"
$PN"M33"2;
"VDDCR_CPU0_M43"
$PN"M43"2;
"VDDCR_CPU0_M44"
$PN"M44"2;
"VDDCR_CPU0_M46"
$PN"M46"2;
"VDDCR_CPU0_M47"
$PN"M47"2;
"VDDCR_CPU0_M49"
$PN"M49"2;
"VDDCR_CPU0_M50"
$PN"M50"2;
"VDDCR_CPU0_M52"
$PN"M52"2;
"VDDCR_CPU0_M53"
$PN"M53"2;
"VDDCR_CPU0_N35"
$PN"N35"2;
"VDDCR_CPU0_N36"
$PN"N36"2;
"VDDCR_CPU0_N40"
$PN"N40"2;
"VDDCR_CPU0_N41"
$PN"N41"2;
"VDDCR_CPU0_T23"
$PN"T23"2;
"VDDCR_CPU0_T24"
$PN"T24"2;
"VDDCR_CPU0_T26"
$PN"T26"2;
"VDDCR_CPU0_T27"
$PN"T27"2;
"VDDCR_CPU0_T29"
$PN"T29"2;
"VDDCR_CPU0_T30"
$PN"T30"2;
"VDDCR_CPU0_T32"
$PN"T32"2;
"VDDCR_CPU0_T33"
$PN"T33"2;
"VDDCR_CPU0_T43"
$PN"T43"2;
"VDDCR_CPU0_T44"
$PN"T44"2;
"VDDCR_CPU0_T46"
$PN"T46"2;
"VDDCR_CPU0_T47"
$PN"T47"2;
"VDDCR_CPU0_T49"
$PN"T49"2;
"VDDCR_CPU0_T50"
$PN"T50"2;
"VDDCR_CPU0_T52"
$PN"T52"2;
"VDDCR_CPU0_T53"
$PN"T53"2;
"VDDCR_CPU0_U35"
$PN"U35"2;
"VDDCR_CPU0_U36"
$PN"U36"2;
"VDDCR_CPU0_U40"
$PN"U40"2;
"VDDCR_CPU0_U41"
$PN"U41"2;
"VDDCR_CPU0_W29"
$PN"W29"2;
"VDDCR_CPU0_W30"
$PN"W30"2;
"VDDCR_CPU0_W32"
$PN"W32"2;
"VDDCR_CPU0_W33"
$PN"W33"2;
"VDDCR_CPU0_W43"
$PN"W43"3;
"VDDCR_CPU0_W44"
$PN"W44"3;
"VDDCR_CPU0_W46"
$PN"W46"3;
"VDDCR_CPU0_W47"
$PN"W47"3;
%"VCC_CORE"
"1","(-7250,6575)","0","pure_quanta_power","I43";
;
HDL_POWER"PVDDCR_CPU0_P0"
CDS_LIB"pure_quanta_power";
"A"3;
%"GENOA_SP5"
"25","(-6075,3350)","0","pure_quanta","I45";
;
LOCATION"U25"
$SEC"25"
CDS_SEC"25"
PART_TYPE"SMLF"
MATERIAL"IO"
VALUE"SOCKET6096_13568-001"
PART_NUMBER"DGA^6000030"
CDS_LMAN_SYM_OUTLINE"-500,3200,500,-3200"
CDS_LIB"pure_quanta"
NEEDS_NO_SIZE"TRUE";
"VDDCR_CPU1_BN46"
$PN"BN46"5;
"VDDCR_CPU1_BN35"
$PN"BN35"5;
"VDDCR_CPU1_BN27"
$PN"BN27"5;
"VDDCR_CPU1_BP32"
$PN"BP32"5;
"VDDCR_CPU1_BP28"
$PN"BP28"5;
"VDDCR_CPU1_BP24"
$PN"BP24"5;
"VDDCR_CPU1_DH51"
$PN"DH51"5;
"VDDCR_CPU1_DH50"
$PN"DH50"5;
"VDDCR_CPU1_DH48"
$PN"DH48"5;
"VDDCR_CPU1_DH47"
$PN"DH47"5;
"VDDCR_CPU1_DH45"
$PN"DH45"5;
"VDDCR_CPU1_DH57"
$PN"DH57"5;
"VDDCR_CPU1_DH56"
$PN"DH56"5;
"VDDCR_CPU1_DH54"
$PN"DH54"5;
"VDDCR_CPU1_DH53"
$PN"DH53"5;
"VDDCR_CPU1_DH44"
$PN"DH44"5;
"VDDCR_CPU1_DH42"
$PN"DH42"5;
"VDDCR_CPU1_DH41"
$PN"DH41"5;
"VDDCR_CPU1_DH35"
$PN"DH35"5;
"VDDCR_CPU1_DH34"
$PN"DH34"5;
"VDDCR_CPU1_DH32"
$PN"DH32"5;
"VDDCR_CPU1_DH31"
$PN"DH31"5;
"VDDCR_CPU1_DH29"
$PN"DH29"5;
"VDDCR_CPU1_DH28"
$PN"DH28"5;
"VDDCR_CPU1_DH26"
$PN"DH26"5;
"VDDCR_CPU1_DH25"
$PN"DH25"5;
"VDDCR_CPU1_DH23"
$PN"DH23"5;
"VDDCR_CPU1_DH22"
$PN"DH22"5;
"VDDCR_CPU1_DH20"
$PN"DH20"5;
"VDDCR_CPU1_DH19"
$PN"DH19"5;
"VDDCR_CPU1_DG57"
$PN"DG57"5;
"VDDCR_CPU1_DG19"
$PN"DG19"5;
"VDDCR_CPU1_DE54"
$PN"DE54"5;
"VDDCR_CPU1_DE51"
$PN"DE51"5;
"VDDCR_CPU1_DE48"
$PN"DE48"5;
"VDDCR_CPU1_DE45"
$PN"DE45"5;
"VDDCR_CPU1_DE42"
$PN"DE42"5;
"VDDCR_CPU1_DE41"
$PN"DE41"5;
"VDDCR_CPU1_DE35"
$PN"DE35"5;
"VDDCR_CPU1_DE34"
$PN"DE34"5;
"VDDCR_CPU1_DE31"
$PN"DE31"5;
"VDDCR_CPU1_DE28"
$PN"DE28"5;
"VDDCR_CPU1_DE25"
$PN"DE25"5;
"VDDCR_CPU1_DE22"
$PN"DE22"5;
"VDDCR_CPU1_DD54"
$PN"DD54"5;
"VDDCR_CPU1_DD51"
$PN"DD51"5;
"VDDCR_CPU1_DD48"
$PN"DD48"5;
"VDDCR_CPU1_DD45"
$PN"DD45"5;
"VDDCR_CPU1_DD42"
$PN"DD42"5;
"VDDCR_CPU1_DD34"
$PN"DD34"5;
"VDDCR_CPU1_DD31"
$PN"DD31"5;
"VDDCR_CPU1_DD28"
$PN"DD28"5;
"VDDCR_CPU1_DD25"
$PN"DD25"5;
"VDDCR_CPU1_DD22"
$PN"DD22"5;
"VDDCR_CPU1_DC41"
$PN"DC41"5;
"VDDCR_CPU1_DC40"
$PN"DC40"5;
"VDDCR_CPU1_DC36"
$PN"DC36"5;
"VDDCR_CPU1_DC35"
$PN"DC35"5;
"VDDCR_CPU1_DB53"
$PN"DB53"5;
"VDDCR_CPU1_DB52"
$PN"DB52"5;
"VDDCR_CPU1_DB50"
$PN"DB50"5;
"VDDCR_CPU1_DB49"
$PN"DB49"5;
"VDDCR_CPU1_DB47"
$PN"DB47"5;
"VDDCR_CPU1_DB46"
$PN"DB46"5;
"VDDCR_CPU1_DB44"
$PN"DB44"5;
"VDDCR_CPU1_DB43"
$PN"DB43"5;
"VDDCR_CPU1_DB33"
$PN"DB33"5;
"VDDCR_CPU1_DB32"
$PN"DB32"5;
"VDDCR_CPU1_DB30"
$PN"DB30"5;
"VDDCR_CPU1_DB29"
$PN"DB29"5;
"VDDCR_CPU1_DB27"
$PN"DB27"5;
"VDDCR_CPU1_DB26"
$PN"DB26"5;
"VDDCR_CPU1_DB24"
$PN"DB24"5;
"VDDCR_CPU1_DB23"
$PN"DB23"5;
"VDDCR_CPU1_DA41"
$PN"DA41"5;
"VDDCR_CPU1_DA40"
$PN"DA40"5;
"VDDCR_CPU1_DA36"
$PN"DA36"5;
"VDDCR_CPU1_DA35"
$PN"DA35"5;
"VDDCR_CPU1_CV53"
$PN"CV53"5;
"VDDCR_CPU1_CV52"
$PN"CV52"5;
"VDDCR_CPU1_CV50"
$PN"CV50"5;
"VDDCR_CPU1_CV49"
$PN"CV49"5;
"VDDCR_CPU1_CV47"
$PN"CV47"5;
"VDDCR_CPU1_CV46"
$PN"CV46"5;
"VDDCR_CPU1_CV44"
$PN"CV44"5;
"VDDCR_CPU1_CV43"
$PN"CV43"5;
"VDDCR_CPU1_CV33"
$PN"CV33"5;
"VDDCR_CPU1_CV32"
$PN"CV32"5;
"VDDCR_CPU1_CV30"
$PN"CV30"5;
"VDDCR_CPU1_CV29"
$PN"CV29"5;
"VDDCR_CPU1_CV27"
$PN"CV27"5;
"VDDCR_CPU1_CV26"
$PN"CV26"5;
"VDDCR_CPU1_CV24"
$PN"CV24"5;
"VDDCR_CPU1_CV23"
$PN"CV23"5;
"VDDCR_CPU1_CU41"
$PN"CU41"5;
"VDDCR_CPU1_CU40"
$PN"CU40"5;
"VDDCR_CPU1_CU36"
$PN"CU36"5;
"VDDCR_CPU1_CU35"
$PN"CU35"5;
"VDDCR_CPU1_CP53"
$PN"CP53"5;
"VDDCR_CPU1_CP52"
$PN"CP52"5;
"VDDCR_CPU1_CP50"
$PN"CP50"5;
"VDDCR_CPU1_CP49"
$PN"CP49"5;
"VDDCR_CPU1_CP47"
$PN"CP47"5;
"VDDCR_CPU1_CP46"
$PN"CP46"5;
"VDDCR_CPU1_CP44"
$PN"CP44"5;
"VDDCR_CPU1_CP43"
$PN"CP43"5;
"VDDCR_CPU1_CP33"
$PN"CP33"5;
"VDDCR_CPU1_CP32"
$PN"CP32"5;
"VDDCR_CPU1_CP30"
$PN"CP30"5;
"VDDCR_CPU1_CP29"
$PN"CP29"5;
"VDDCR_CPU1_CP27"
$PN"CP27"5;
"VDDCR_CPU1_CP26"
$PN"CP26"5;
"VDDCR_CPU1_CP24"
$PN"CP24"5;
"VDDCR_CPU1_CP23"
$PN"CP23"5;
"VDDCR_CPU1_CN41"
$PN"CN41"5;
"VDDCR_CPU1_CN40"
$PN"CN40"5;
"VDDCR_CPU1_CN36"
$PN"CN36"5;
"VDDCR_CPU1_CN35"
$PN"CN35"5;
"VDDCR_CPU1_CL47"
$PN"CL47"5;
"VDDCR_CPU1_CL46"
$PN"CL46"5;
"VDDCR_CPU1_CL44"
$PN"CL44"5;
"VDDCR_CPU1_CL43"
$PN"CL43"5;
"VDDCR_CPU1_CL33"
$PN"CL33"5;
"VDDCR_CPU1_CL32"
$PN"CL32"5;
"VDDCR_CPU1_CL30"
$PN"CL30"4;
"VDDCR_CPU1_CL29"
$PN"CL29"4;
"VDDCR_CPU1_CK41"
$PN"CK41"4;
"VDDCR_CPU1_CK40"
$PN"CK40"4;
"VDDCR_CPU1_CK36"
$PN"CK36"4;
"VDDCR_CPU1_CK35"
$PN"CK35"4;
"VDDCR_CPU1_CH53"
$PN"CH53"4;
"VDDCR_CPU1_CH52"
$PN"CH52"4;
"VDDCR_CPU1_CH50"
$PN"CH50"4;
"VDDCR_CPU1_CH49"
$PN"CH49"4;
"VDDCR_CPU1_CH47"
$PN"CH47"4;
"VDDCR_CPU1_CH46"
$PN"CH46"4;
"VDDCR_CPU1_CH44"
$PN"CH44"4;
"VDDCR_CPU1_CH43"
$PN"CH43"4;
"VDDCR_CPU1_CH33"
$PN"CH33"4;
"VDDCR_CPU1_CH32"
$PN"CH32"4;
"VDDCR_CPU1_CH30"
$PN"CH30"4;
"VDDCR_CPU1_CH29"
$PN"CH29"4;
"VDDCR_CPU1_CH27"
$PN"CH27"4;
"VDDCR_CPU1_CH26"
$PN"CH26"4;
"VDDCR_CPU1_CH24"
$PN"CH24"4;
"VDDCR_CPU1_CH23"
$PN"CH23"4;
"VDDCR_CPU1_CG41"
$PN"CG41"4;
"VDDCR_CPU1_CG40"
$PN"CG40"4;
"VDDCR_CPU1_CG36"
$PN"CG36"4;
"VDDCR_CPU1_CG35"
$PN"CG35"4;
"VDDCR_CPU1_CD53"
$PN"CD53"4;
"VDDCR_CPU1_CD52"
$PN"CD52"4;
"VDDCR_CPU1_CD50"
$PN"CD50"4;
"VDDCR_CPU1_CD49"
$PN"CD49"4;
"VDDCR_CPU1_CD47"
$PN"CD47"4;
"VDDCR_CPU1_CD46"
$PN"CD46"4;
"VDDCR_CPU1_CD44"
$PN"CD44"4;
"VDDCR_CPU1_CD43"
$PN"CD43"4;
"VDDCR_CPU1_CD33"
$PN"CD33"4;
"VDDCR_CPU1_CD32"
$PN"CD32"4;
"VDDCR_CPU1_CD30"
$PN"CD30"4;
"VDDCR_CPU1_CD29"
$PN"CD29"4;
"VDDCR_CPU1_CD27"
$PN"CD27"4;
"VDDCR_CPU1_CD26"
$PN"CD26"4;
"VDDCR_CPU1_CD24"
$PN"CD24"4;
"VDDCR_CPU1_CD23"
$PN"CD23"4;
"VDDCR_CPU1_CC41"
$PN"CC41"4;
"VDDCR_CPU1_CC40"
$PN"CC40"4;
"VDDCR_CPU1_CC36"
$PN"CC36"4;
"VDDCR_CPU1_CC35"
$PN"CC35"4;
"VDDCR_CPU1_BY53"
$PN"BY53"4;
"VDDCR_CPU1_BY52"
$PN"BY52"4;
"VDDCR_CPU1_BY50"
$PN"BY50"4;
"VDDCR_CPU1_BY49"
$PN"BY49"4;
"VDDCR_CPU1_BY47"
$PN"BY47"4;
"VDDCR_CPU1_BY46"
$PN"BY46"4;
"VDDCR_CPU1_BY44"
$PN"BY44"4;
"VDDCR_CPU1_BY43"
$PN"BY43"4;
"VDDCR_CPU1_BY33"
$PN"BY33"4;
"VDDCR_CPU1_BY32"
$PN"BY32"4;
"VDDCR_CPU1_BY30"
$PN"BY30"4;
"VDDCR_CPU1_BY29"
$PN"BY29"4;
"VDDCR_CPU1_BY27"
$PN"BY27"4;
"VDDCR_CPU1_BY26"
$PN"BY26"4;
"VDDCR_CPU1_BY24"
$PN"BY24"4;
"VDDCR_CPU1_BY23"
$PN"BY23"4;
"VDDCR_CPU1_BW41"
$PN"BW41"4;
"VDDCR_CPU1_BW40"
$PN"BW40"4;
"VDDCR_CPU1_BW36"
$PN"BW36"4;
"VDDCR_CPU1_BW35"
$PN"BW35"4;
"VDDCR_CPU1_BT53"
$PN"BT53"4;
"VDDCR_CPU1_BT52"
$PN"BT52"4;
"VDDCR_CPU1_BT50"
$PN"BT50"4;
"VDDCR_CPU1_BT49"
$PN"BT49"4;
"VDDCR_CPU1_BT47"
$PN"BT47"4;
"VDDCR_CPU1_BT46"
$PN"BT46"4;
"VDDCR_CPU1_BT44"
$PN"BT44"4;
"VDDCR_CPU1_BT43"
$PN"BT43"4;
"VDDCR_CPU1_BT33"
$PN"BT33"4;
"VDDCR_CPU1_BT32"
$PN"BT32"4;
"VDDCR_CPU1_BT30"
$PN"BT30"4;
"VDDCR_CPU1_BT29"
$PN"BT29"4;
"VDDCR_CPU1_BT27"
$PN"BT27"4;
"VDDCR_CPU1_BT26"
$PN"BT26"4;
"VDDCR_CPU1_BT24"
$PN"BT24"4;
"VDDCR_CPU1_BT23"
$PN"BT23"4;
"VDDCR_CPU1_BR52"
$PN"BR52"4;
"VDDCR_CPU1_BR50"
$PN"BR50"4;
"VDDCR_CPU1_BR48"
$PN"BR48"4;
"VDDCR_CPU1_BR46"
$PN"BR46"4;
"VDDCR_CPU1_BR44"
$PN"BR44"4;
"VDDCR_CPU1_BR42"
$PN"BR42"4;
"VDDCR_CPU1_BR40"
$PN"BR40"4;
"VDDCR_CPU1_BR35"
$PN"BR35"4;
"VDDCR_CPU1_BR33"
$PN"BR33"4;
"VDDCR_CPU1_BR31"
$PN"BR31"4;
"VDDCR_CPU1_BR29"
$PN"BR29"4;
"VDDCR_CPU1_BR27"
$PN"BR27"4;
"VDDCR_CPU1_BR25"
$PN"BR25"4;
"VDDCR_CPU1_BR23"
$PN"BR23"4;
"VDDCR_CPU1_BP49"
$PN"BP49"4;
"VDDCR_CPU1_BP47"
$PN"BP47"4;
"VDDCR_CPU1_BP45"
$PN"BP45"4;
"VDDCR_CPU1_BP43"
$PN"BP43"4;
"VDDCR_CPU1_BP41"
$PN"BP41"4;
"VDDCR_CPU1_BP39"
$PN"BP39"4;
"VDDCR_CPU1_BP36"
$PN"BP36"4;
"VDDCR_CPU1_BP34"
$PN"BP34"4;
"VDDCR_CPU1_BP30"
$PN"BP30"4;
"VDDCR_CPU1_BP26"
$PN"BP26"4;
"VDDCR_CPU1_BN50"
$PN"BN50"4;
"VDDCR_CPU1_BN42"
$PN"BN42"4;
"VDDCR_CPU1_BN31"
$PN"BN31"4;
%"VCC_CORE"
"1","(-5275,6475)","0","pure_quanta_power","I46";
;
HDL_POWER"PVDDCR_CPU1_P0"
CDS_LIB"pure_quanta_power";
"A"5;
%"VCC_CORE"
"1","(-6900,6225)","0","pure_quanta_power","I47";
;
HDL_POWER"PVDDCR_CPU1_P0"
CDS_LIB"pure_quanta_power";
"A"4;
%"GENOA_SP5"
"26","(-4250,4575)","0","pure_quanta","I50";
;
LOCATION"U25"
$SEC"26"
CDS_SEC"26"
PART_TYPE"SMLF"
MATERIAL"IO"
VALUE"SOCKET6096_13568-001"
PART_NUMBER"DGA^6000030"
CDS_LMAN_SYM_OUTLINE"-450,1650,450,-1650"
NEEDS_NO_SIZE"TRUE"
CDS_LIB"pure_quanta";
"VDDCR_SOC_BG22"
$PN"BG22"10;
"VDDCR_SOC_BG24"
$PN"BG24"10;
"VDDCR_SOC_BG26"
$PN"BG26"10;
"VDDCR_SOC_BG28"
$PN"BG28"10;
"VDDCR_SOC_BG48"
$PN"BG48"10;
"VDDCR_SOC_BH23"
$PN"BH23"10;
"VDDCR_SOC_BH25"
$PN"BH25"10;
"VDDCR_SOC_BH48"
$PN"BH48"10;
"VDDCR_SOC_BJ4"
$PN"BJ4"10;
"VDDCR_SOC_BJ11"
$PN"BJ11"10;
"VDDCR_SOC_BJ48"
$PN"BJ48"10;
"VDDCR_SOC_BM5"
$PN"BM5"10;
"VDDCR_SOC_BF48"
$PN"BF48"10;
"VDDCR_SOC_BF27"
$PN"BF27"10;
"VDDCR_SOC_BF25"
$PN"BF25"10;
"VDDCR_SOC_BF23"
$PN"BF23"10;
"VDDCR_SOC_BD48"
$PN"BD48"10;
"VDDCR_SOC_BD28"
$PN"BD28"10;
"VDDCR_SOC_BD26"
$PN"BD26"10;
"VDDCR_SOC_BD24"
$PN"BD24"10;
"VDDCR_SOC_BD22"
$PN"BD22"10;
"VDDCR_SOC_BD19"
$PN"BD19"10;
"VDDCR_SOC_BD12"
$PN"BD12"10;
"VDDCR_SOC_BD5"
$PN"BD5"10;
"VDDCR_SOC_BC48"
$PN"BC48"10;
"VDDCR_SOC_BC27"
$PN"BC27"10;
"VDDCR_SOC_BC25"
$PN"BC25"10;
"VDDCR_SOC_BC23"
$PN"BC23"10;
"VDDCR_SOC_BB49"
$PN"BB49"10;
"VDDCR_SOC_BB28"
$PN"BB28"10;
"VDDCR_SOC_BB26"
$PN"BB26"10;
"VDDCR_SOC_BB24"
$PN"BB24"10;
"VDDCR_SOC_BB22"
$PN"BB22"10;
"VDDCR_SOC_BA48"
$PN"BA48"10;
"VDDCR_SOC_BA27"
$PN"BA27"10;
"VDDCR_SOC_BA25"
$PN"BA25"10;
"VDDCR_SOC_BA23"
$PN"BA23"10;
"VDDCR_SOC_BA18"
$PN"BA18"10;
"VDDCR_SOC_BA11"
$PN"BA11"10;
"VDDCR_SOC_BA4"
$PN"BA4"10;
"VDDCR_SOC_AY49"
$PN"AY49"10;
"VDDCR_SOC_AY28"
$PN"AY28"10;
"VDDCR_SOC_AY26"
$PN"AY26"10;
"VDDCR_SOC_AY24"
$PN"AY24"10;
"VDDCR_SOC_AY22"
$PN"AY22"10;
"VDDCR_SOC_AW48"
$PN"AW48"10;
"VDDCR_SOC_AW27"
$PN"AW27"10;
"VDDCR_SOC_AW25"
$PN"AW25"10;
"VDDCR_SOC_AW23"
$PN"AW23"10;
"VDDCR_SOC_AV47"
$PN"AV47"10;
"VDDCR_SOC_AV45"
$PN"AV45"10;
"VDDCR_SOC_AV43"
$PN"AV43"10;
"VDDCR_SOC_AV41"
$PN"AV41"6;
"VDDCR_SOC_AV39"
$PN"AV39"6;
"VDDCR_SOC_AV36"
$PN"AV36"6;
"VDDCR_SOC_AV34"
$PN"AV34"6;
"VDDCR_SOC_AV32"
$PN"AV32"6;
"VDDCR_SOC_AV30"
$PN"AV30"6;
"VDDCR_SOC_AV28"
$PN"AV28"6;
"VDDCR_SOC_AV26"
$PN"AV26"6;
"VDDCR_SOC_AV24"
$PN"AV24"6;
"VDDCR_SOC_AV22"
$PN"AV22"6;
"VDDCR_SOC_AV19"
$PN"AV19"6;
"VDDCR_SOC_AV12"
$PN"AV12"6;
"VDDCR_SOC_AV5"
$PN"AV5"6;
"VDDCR_SOC_AU40"
$PN"AU40"6;
"VDDCR_SOC_AU35"
$PN"AU35"6;
"VDDCR_SOC_AU31"
$PN"AU31"6;
"VDDCR_SOC_AU27"
$PN"AU27"6;
"VDDCR_SOC_AU23"
$PN"AU23"6;
"VDDCR_SOC_AT22"
$PN"AT22"6;
"VDDCR_SOC_AR18"
$PN"AR18"6;
"VDDCR_SOC_AR11"
$PN"AR11"6;
"VDDCR_SOC_AR4"
$PN"AR4"6;
"VDDCR_SOC_AM22"
$PN"AM22"6;
"VDDCR_SOC_AM19"
$PN"AM19"6;
"VDDCR_SOC_AM12"
$PN"AM12"6;
"VDDCR_SOC_AM5"
$PN"AM5"6;
"VDDCR_SOC_AJ18"
$PN"AJ18"6;
"VDDCR_SOC_AJ11"
$PN"AJ11"6;
"VDDCR_SOC_AJ4"
$PN"AJ4"6;
"VDDCR_SOC_AH22"
$PN"AH22"6;
"VDDCR_SOC_AF19"
$PN"AF19"6;
"VDDCR_SOC_AF12"
$PN"AF12"6;
"VDDCR_SOC_AF5"
$PN"AF5"6;
"VDDCR_SOC_AD22"
$PN"AD22"6;
"VDDCR_SOC_AC18"
$PN"AC18"6;
"VDDCR_SOC_AC11"
$PN"AC11"6;
"VDDCR_SOC_AC4"
$PN"AC4"6;
"VDDCR_SOC_AA22"
$PN"AA22"6;
"VDDCR_SOC_Y19"
$PN"Y19"6;
"VDDCR_SOC_Y12"
$PN"Y12"6;
"VDDCR_SOC_Y5"
$PN"Y5"6;
"VDDCR_SOC_V22"
$PN"V22"6;
"VDDCR_SOC_U18"
$PN"U18"6;
"VDDCR_SOC_U11"
$PN"U11"6;
"VDDCR_SOC_U4"
$PN"U4"6;
"VDDCR_SOC_P22"
$PN"P22"6;
"VDDCR_SOC_P19"
$PN"P19"6;
"VDDCR_SOC_P12"
$PN"P12"6;
"VDDCR_SOC_P5"
$PN"P5"6;
"VDDCR_SOC_L18"
$PN"L18"6;
"VDDCR_SOC_L11"
$PN"L11"6;
"VDDCR_SOC_L4"
$PN"L4"6;
"VDDCR_SOC_K22"
$PN"K22"6;
"VDDCR_SOC_H19"
$PN"H19"6;
"VDDCR_SOC_H12"
$PN"H12"6;
"VDDCR_SOC_H5"
$PN"H5"6;
"VDDCR_SOC_E11"
$PN"E11"6;
"VDDCR_SOC_E4"
$PN"E4"6;
"VDDCR_SOC_C4"
$PN"C4"6;
"VDDCR_SOC_B5"
$PN"B5"6;
%"VCC_CORE"
"1","(-8900,6575)","0","pure_quanta_power","I51";
;
HDL_POWER"PVDDCR_CPU0_P0"
CDS_LIB"pure_quanta_power";
"A"2;
%"VCC_CORE"
"1","(-3300,6600)","0","pure_quanta_power","I52";
;
HDL_POWER"PVDD11_S3_P0"
CDS_LIB"pure_quanta_power";
"A"9;
%"UNIVERSAL_POWER"
"1","(-3475,2825)","0","pure_quanta_power","I53";
;
HDL_POWER"PVDD18_S5_P0"
CDS_LIB"pure_quanta_power";
"A"8;
%"UNIVERSAL_POWER"
"1","(-3475,1075)","0","pure_quanta_power","I55";
;
HDL_POWER"PVDD_33_S5"
CDS_LIB"pure_quanta_power";
"A"7;
%"VCC_CORE"
"1","(-3500,6150)","0","pure_quanta_power","I56";
;
HDL_POWER"PVDDCR_SOC_P0"
CDS_LIB"pure_quanta_power";
"A"10;
%"VCC_CORE"
"1","(-4975,6150)","0","pure_quanta_power","I57";
;
HDL_POWER"PVDDCR_SOC_P0"
CDS_LIB"pure_quanta_power";
"A"6;
END.
